# S9S_MB_2U (Grand Teton) — schematic netlist excerpt (pin names and nets, part order shuffled) for the footprints in the layout excerpt that follows; sources: Cadence DE-HDL packaged netlist, KiCad conversion of 03242023_DA0F0TMBIJ0_F0T_Motherboard_J_brd_V01_OCP.brd

R3125  Q_RES  0 5% CHIP  pkg 0402LF  page 236 : A = SMB_S3M_CPU1_PIROM_3V3AUX_SCL_R ; B = SMB_S3M_CPU1_PIROM_3V3AUX_SCL
C890  Q_CAP_DIFFBUS  DIFF BUS_0.22UF 6.3V 20% X6S  pkg C0201  page 174 : \1\ = P5E_CPU0_PE3_TX_C_DN<5> ; \2\ = P5E_CPU0_PE3_TX_DN<5>
R2659  Q_RES  0 5% CHIP  pkg 0402LF  page 207 : A = CLK_100M_SWB_R_DP ; B = CLK_100M_SWB_DP

(kicad_pcb
	(version 20260206)
	(generator "pcbnew")
	(generator_version "10.0")
	(general
		(thickness 1.6)
		(legacy_teardrops no)
	)
	(paper "A4")
	(title_block
		(title "03242023_DA0F0TMBIJ0_F0T_Motherboard_J_brd_V01_OCP.brd")
		(comment 1 "Grand Teton / footprints 2005-2007 of 6105")
	)
	(layers
		(0 "F.Cu" signal "TOP")
		(4 "In1.Cu" signal "GND")
		(6 "In2.Cu" signal "IN1")
		(8 "In3.Cu" signal "GND1")
		(10 "In4.Cu" signal "IN2")
		(12 "In5.Cu" signal "GND2")
		(14 "In6.Cu" signal "IN3")
		(16 "In7.Cu" signal "GND3")
		(18 "In8.Cu" signal "VCC")
		(20 "In9.Cu" signal "VCC1")
		(22 "In10.Cu" signal "GND4")
		(24 "In11.Cu" signal "IN4")
		(26 "In12.Cu" signal "GND5")
		(28 "In13.Cu" signal "IN5")
		(30 "In14.Cu" signal "GND6")
		(32 "In15.Cu" signal "IN6")
		(34 "In16.Cu" signal "GND7")
		(2 "B.Cu" signal "BOTTOM")
		(9 "F.Adhes" user "F.Adhesive")
		(11 "B.Adhes" user "B.Adhesive")
		(13 "F.Paste" user "Package Geometry/Pastemask Top")
		(15 "B.Paste" user "Package Geometry/Pastemask Bottom")
		(5 "F.SilkS" user "Ref Des/Silkscreen Top")
		(7 "B.SilkS" user "Ref Des/Silkscreen Bottom")
		(1 "F.Mask" user "Board Geometry/Soldermask Top")
		(3 "B.Mask" user "Board Geometry/Soldermask Bottom")
		(17 "Dwgs.User" user "User.Drawings")
		(19 "Cmts.User" user "User.Comments")
		(21 "Eco1.User" user "User.Eco1")
		(23 "Eco2.User" user "User.Eco2")
		(25 "Edge.Cuts" user "Board Geometry/Outline")
		(27 "Margin" user)
		(31 "F.CrtYd" user "Package Geometry/Place Bound Top")
		(29 "B.CrtYd" user "Package Geometry/Place Bound Bottom")
		(35 "F.Fab" user "Ref Des/Assembly Top")
		(33 "B.Fab" user "Ref Des/Assembly Bottom")
	)
	(footprint ""
		(layer "F.Cu")
		(at 112.26546 -418.027358 90)
		(property "Reference" "R2659"
			(at 0 0 90)
			(layer "F.SilkS")
			(hide yes)
			(effects
				(font
					(size 1.27 1.27)
				)
			)
		)
		(property "Value" ""
			(at 0 0 90)
			(layer "F.Fab")
			(effects
				(font
					(size 1.27 1.27)
				)
			)
		)
		(duplicate_pad_numbers_are_jumpers no)
		(fp_line
			(start -0.33147 -0.4064)
			(end 0.31877 -0.4064)
			(stroke
				(width 0.1524)
				(type default)
			)
			(layer "F.SilkS")
		)
		(fp_line
			(start 0.7874 -0.01524)
			(end 0.7874 0.4064)
			(stroke
				(width 0.1524)
				(type default)
			)
			(layer "F.SilkS")
		)
		(fp_line
			(start 0.7874 0.4064)
			(end -0.7874 0.4064)
			(stroke
				(width 0.1524)
				(type default)
			)
			(layer "F.SilkS")
		)
		(fp_line
			(start -0.7874 0.4064)
			(end -0.7874 -0.0254)
			(stroke
				(width 0.1524)
				(type default)
			)
			(layer "F.SilkS")
		)
		(fp_line
			(start -0.12065 -0.305054)
			(end -0.12065 -0.2794)
			(stroke
				(width 0.1)
				(type default)
			)
			(layer "F.Fab")
		)
		(fp_line
			(start -0.67945 -0.305054)
			(end -0.12065 -0.305054)
			(stroke
				(width 0.1)
				(type default)
			)
			(layer "F.Fab")
		)
		(fp_line
			(start 0.67945 -0.3048)
			(end 0.67945 0.3048)
			(stroke
				(width 0.1)
				(type default)
			)
			(layer "F.Fab")
		)
		(fp_line
			(start 0.12065 -0.3048)
			(end 0.67945 -0.3048)
			(stroke
				(width 0.1)
				(type default)
			)
			(layer "F.Fab")
		)
		(fp_line
			(start 0.12065 -0.2794)
			(end 0.12065 -0.3048)
			(stroke
				(width 0.1)
				(type default)
			)
			(layer "F.Fab")
		)
		(fp_line
			(start -0.12065 -0.2794)
			(end 0.12065 -0.2794)
			(stroke
				(width 0.1)
				(type default)
			)
			(layer "F.Fab")
		)
		(fp_line
			(start 0.120396 0.2794)
			(end -0.12065 0.2794)
			(stroke
				(width 0.1)
				(type default)
			)
			(layer "F.Fab")
		)
		(fp_line
			(start -0.12065 0.2794)
			(end -0.12065 0.3048)
			(stroke
				(width 0.1)
				(type default)
			)
			(layer "F.Fab")
		)
		(fp_line
			(start 0.67945 0.3048)
			(end 0.120396 0.3048)
			(stroke
				(width 0.1)
				(type default)
			)
			(layer "F.Fab")
		)
		(fp_line
			(start 0.120396 0.3048)
			(end 0.120396 0.2794)
			(stroke
				(width 0.1)
				(type default)
			)
			(layer "F.Fab")
		)
		(fp_line
			(start -0.12065 0.3048)
			(end -0.67945 0.3048)
			(stroke
				(width 0.1)
				(type default)
			)
			(layer "F.Fab")
		)
		(fp_line
			(start -0.67945 0.3048)
			(end -0.67945 -0.305054)
			(stroke
				(width 0.1)
				(type default)
			)
			(layer "F.Fab")
		)
		(pad "1" smd circle
			(at -0.40005 0 90)
			(size 0 0)
			(layers "F.Cu" "F.Mask" "F.Paste")
			(net "CLK_100M_SWB_R_DP")
		)
		(pad "2" smd circle
			(at 0.40005 0 90)
			(size 0 0)
			(layers "F.Cu" "F.Mask" "F.Paste")
			(net "CLK_100M_SWB_DP")
		)
	)
	(footprint ""
		(layer "F.Cu")
		(at 403.37613 -408.517344 -90)
		(property "Reference" "C890"
			(at 0 0 270)
			(layer "F.SilkS")
			(hide yes)
			(effects
				(font
					(size 1.27 1.27)
				)
			)
		)
		(property "Value" ""
			(at 0 0 270)
			(layer "F.Fab")
			(effects
				(font
					(size 1.27 1.27)
				)
			)
		)
		(duplicate_pad_numbers_are_jumpers no)
		(fp_line
			(start -0.299974 0.150114)
			(end -0.299974 -0.150114)
			(stroke
				(width 0.1)
				(type default)
			)
			(layer "F.Fab")
		)
		(fp_line
			(start 0.299974 0.150114)
			(end -0.299974 0.150114)
			(stroke
				(width 0.1)
				(type default)
			)
			(layer "F.Fab")
		)
		(fp_line
			(start -0.299974 -0.150114)
			(end 0.299974 -0.150114)
			(stroke
				(width 0.1)
				(type default)
			)
			(layer "F.Fab")
		)
		(fp_line
			(start 0.299974 -0.150114)
			(end 0.299974 0.150114)
			(stroke
				(width 0.1)
				(type default)
			)
			(layer "F.Fab")
		)
		(pad "1" smd rect
			(at -0.2667 0 270)
			(size 0.3048 0.381)
			(layers "F.Cu" "F.Mask" "F.Paste")
			(net "P5E_CPU0_PE3_TX_C_DN<5>")
		)
		(pad "2" smd rect
			(at 0.2667 0 270)
			(size 0.3048 0.381)
			(layers "F.Cu" "F.Mask" "F.Paste")
			(net "P5E_CPU0_PE3_TX_DN<5>")
		)
	)
	(footprint ""
		(layer "F.Cu")
		(at 159.317944 -81.902554 90)
		(property "Reference" "R3125"
			(at 0 0 90)
			(layer "F.SilkS")
			(hide yes)
			(effects
				(font
					(size 1.27 1.27)
				)
			)
		)
		(property "Value" ""
			(at 0 0 90)
			(layer "F.Fab")
			(effects
				(font
					(size 1.27 1.27)
				)
			)
		)
		(duplicate_pad_numbers_are_jumpers no)
		(fp_line
			(start 0.7874 -0.4064)
			(end 0.7874 0.4064)
			(stroke
				(width 0.1524)
				(type default)
			)
			(layer "F.SilkS")
		)
		(fp_line
			(start -0.7874 -0.4064)
			(end 0.7874 -0.4064)
			(stroke
				(width 0.1524)
				(type default)
			)
			(layer "F.SilkS")
		)
		(fp_line
			(start 0.7874 0.4064)
			(end -0.7874 0.4064)
			(stroke
				(width 0.1524)
				(type default)
			)
			(layer "F.SilkS")
		)
		(fp_line
			(start -0.7874 0.4064)
			(end -0.7874 -0.4064)
			(stroke
				(width 0.1524)
				(type default)
			)
			(layer "F.SilkS")
		)
		(fp_line
			(start -0.12065 -0.305054)
			(end -0.12065 -0.2794)
			(stroke
				(width 0.1)
				(type default)
			)
			(layer "F.Fab")
		)
		(fp_line
			(start -0.67945 -0.305054)
			(end -0.12065 -0.305054)
			(stroke
				(width 0.1)
				(type default)
			)
			(layer "F.Fab")
		)
		(fp_line
			(start 0.67945 -0.3048)
			(end 0.67945 0.3048)
			(stroke
				(width 0.1)
				(type default)
			)
			(layer "F.Fab")
		)
		(fp_line
			(start 0.12065 -0.3048)
			(end 0.67945 -0.3048)
			(stroke
				(width 0.1)
				(type default)
			)
			(layer "F.Fab")
		)
		(fp_line
			(start 0.12065 -0.2794)
			(end 0.12065 -0.3048)
			(stroke
				(width 0.1)
				(type default)
			)
			(layer "F.Fab")
		)
		(fp_line
			(start -0.12065 -0.2794)
			(end 0.12065 -0.2794)
			(stroke
				(width 0.1)
				(type default)
			)
			(layer "F.Fab")
		)
		(fp_line
			(start 0.120396 0.2794)
			(end -0.12065 0.2794)
			(stroke
				(width 0.1)
				(type default)
			)
			(layer "F.Fab")
		)
		(fp_line
			(start -0.12065 0.2794)
			(end -0.12065 0.3048)
			(stroke
				(width 0.1)
				(type default)
			)
			(layer "F.Fab")
		)
		(fp_line
			(start 0.67945 0.3048)
			(end 0.120396 0.3048)
			(stroke
				(width 0.1)
				(type default)
			)
			(layer "F.Fab")
		)
		(fp_line
			(start 0.120396 0.3048)
			(end 0.120396 0.2794)
			(stroke
				(width 0.1)
				(type default)
			)
			(layer "F.Fab")
		)
		(fp_line
			(start -0.12065 0.3048)
			(end -0.67945 0.3048)
			(stroke
				(width 0.1)
				(type default)
			)
			(layer "F.Fab")
		)
		(fp_line
			(start -0.67945 0.3048)
			(end -0.67945 -0.305054)
			(stroke
				(width 0.1)
				(type default)
			)
			(layer "F.Fab")
		)
		(pad "1" smd circle
			(at -0.40005 0 90)
			(size 0 0)
			(layers "F.Cu" "F.Mask" "F.Paste")
			(net "SMB_S3M_CPU1_PIROM_3V3AUX_SCL_R")
		)
		(pad "2" smd circle
			(at 0.40005 0 90)
			(size 0 0)
			(layers "F.Cu" "F.Mask" "F.Paste")
			(net "SMB_S3M_CPU1_PIROM_3V3AUX_SCL")
		)
	)
)
